(kicad_pcb
	(version 20260206)
	(generator "pcbnew")
	(generator_version "10.0")
	(general
		(thickness 1.6)
		(legacy_teardrops no)
	)
	(paper "A4")
	(title_block
		(title "peb — Lightning_PEB_BRD.brd")
		(comment 1 "Lightning (Wiwynn / Facebook NVMe JBOF) / footprints 943-949 of 2563")
	)
	(layers
		(0 "F.Cu" signal "TOP")
		(4 "In1.Cu" signal "L2GND")
		(6 "In2.Cu" signal "L3")
		(8 "In3.Cu" signal "L4VCC")
		(10 "In4.Cu" signal "L5VCC")
		(12 "In5.Cu" signal "L6")
		(14 "In6.Cu" signal "L7GND")
		(2 "B.Cu" signal "BOTTOM")
		(9 "F.Adhes" user "F.Adhesive")
		(11 "B.Adhes" user "B.Adhesive")
		(13 "F.Paste" user "Package Geometry/Pastemask Top")
		(15 "B.Paste" user "Package Geometry/Pastemask Bottom")
		(5 "F.SilkS" user "Ref Des/Silkscreen Top")
		(7 "B.SilkS" user "Ref Des/Silkscreen Bottom")
		(1 "F.Mask" user "Board Geometry/Soldermask Top")
		(3 "B.Mask" user "Board Geometry/Soldermask Bottom")
		(17 "Dwgs.User" user "User.Drawings")
		(19 "Cmts.User" user "User.Comments")
		(21 "Eco1.User" user "User.Eco1")
		(23 "Eco2.User" user "User.Eco2")
		(25 "Edge.Cuts" user "Board Geometry/Outline")
		(27 "Margin" user)
		(31 "F.CrtYd" user "Package Geometry/Place Bound Top")
		(29 "B.CrtYd" user "Package Geometry/Place Bound Bottom")
		(35 "F.Fab" user "Ref Des/Assembly Top")
		(33 "B.Fab" user "Ref Des/Assembly Bottom")
	)
	(footprint ""
		(layer "F.Cu")
		(at 209.325972 -12.542266 180)
		(property "Reference" "R7889"
			(at 0 0 180)
			(layer "F.SilkS")
			(hide yes)
			(effects
				(font
					(size 1.27 1.27)
				)
			)
		)
		(property "Value" "0R2J-2-GP"
			(at 0.064008 -3.993896 180)
			(unlocked yes)
			(layer "F.Fab")
			(hide yes)
			(effects
				(font
					(size 1.016 1.016)
					(thickness 0.1524)
				)
			)
		)
		(property "Device Type" "R402H16"
			(at 0.064008 -5.517896 180)
			(unlocked yes)
			(layer "F.Fab")
			(hide yes)
			(effects
				(font
					(size 1.016 1.016)
					(thickness 0.1524)
				)
			)
		)
		(duplicate_pad_numbers_are_jumpers no)
		(fp_line
			(start 0.508 -0.9398)
			(end -0.508 -0.9398)
			(stroke
				(width 0.1524)
				(type default)
			)
			(layer "F.SilkS")
		)
		(fp_line
			(start -0.508 -0.9398)
			(end -0.508 0.9398)
			(stroke
				(width 0.1524)
				(type default)
			)
			(layer "F.SilkS")
		)
		(fp_rect
			(start -0.508 0.9398)
			(end 0.508 -0.9398)
			(stroke
				(width 0)
				(type default)
			)
			(fill no)
			(layer "F.CrtYd")
		)
		(fp_rect
			(start -0.508 0.9398)
			(end 0.508 -0.9398)
			(stroke
				(width 0)
				(type default)
			)
			(fill no)
			(layer "F.Fab")
		)
		(pad "1" smd custom
			(at 0 -0.4445 180)
			(size 0.1397 0.1397)
			(layers "F.Cu" "F.Mask" "F.Paste")
			(net "BMC_ID_LED")
			(options
				(clearance outline)
				(anchor circle)
			)
			(primitives
				(gr_poly
					(pts
						(arc
							(start -0.1778 -0.2794)
							(mid -0.249642 -0.249642)
							(end -0.2794 -0.1778)
						)
						(arc
							(start -0.2794 0.1778)
							(mid -0.249642 0.249642)
							(end -0.1778 0.2794)
						)
						(arc
							(start 0.1778 0.2794)
							(mid 0.249642 0.249642)
							(end 0.2794 0.1778)
						)
						(arc
							(start 0.2794 -0.1778)
							(mid 0.249642 -0.249642)
							(end 0.1778 -0.2794)
						)
					)
					(width 0)
					(fill yes)
				)
			)
		)
		(pad "2" smd custom
			(at 0 0.4445 180)
			(size 0.1397 0.1397)
			(layers "F.Cu" "F.Mask" "F.Paste")
			(net "BMC_ID_LED_R")
			(options
				(clearance outline)
				(anchor circle)
			)
			(primitives
				(gr_poly
					(pts
						(arc
							(start -0.1778 -0.2794)
							(mid -0.249642 -0.249642)
							(end -0.2794 -0.1778)
						)
						(arc
							(start -0.2794 0.1778)
							(mid -0.249642 0.249642)
							(end -0.1778 0.2794)
						)
						(arc
							(start 0.1778 0.2794)
							(mid 0.249642 0.249642)
							(end 0.2794 0.1778)
						)
						(arc
							(start 0.2794 -0.1778)
							(mid 0.249642 -0.249642)
							(end 0.1778 -0.2794)
						)
					)
					(width 0)
					(fill yes)
				)
			)
		)
	)
	(footprint ""
		(layer "F.Cu")
		(at 145.177002 -70.182232 -90)
		(property "Reference" "PC199"
			(at 0 0 270)
			(layer "F.SilkS")
			(hide yes)
			(effects
				(font
					(size 1.27 1.27)
				)
			)
		)
		(property "Value" "SC22U25V6KX-GP-U"
			(at -2.860802 -5.279644 270)
			(unlocked yes)
			(layer "F.Fab")
			(hide yes)
			(effects
				(font
					(size 1.016 1.016)
					(thickness 0.1524)
				)
			)
		)
		(property "Device Type" "C1206-TO0D3H75"
			(at -2.860802 -6.803644 270)
			(unlocked yes)
			(layer "F.Fab")
			(hide yes)
			(effects
				(font
					(size 1.016 1.016)
					(thickness 0.1524)
				)
			)
		)
		(duplicate_pad_numbers_are_jumpers no)
		(fp_line
			(start -1.3081 2.3749)
			(end -1.3081 -2.3749)
			(stroke
				(width 0.1524)
				(type default)
			)
			(layer "F.SilkS")
		)
		(fp_line
			(start 1.3081 2.3749)
			(end -1.3081 2.3749)
			(stroke
				(width 0.1524)
				(type default)
			)
			(layer "F.SilkS")
		)
		(fp_line
			(start -1.3081 -2.3749)
			(end 1.3081 -2.3749)
			(stroke
				(width 0.1524)
				(type default)
			)
			(layer "F.SilkS")
		)
		(fp_line
			(start 1.3081 -2.3749)
			(end 1.3081 2.3749)
			(stroke
				(width 0.1524)
				(type default)
			)
			(layer "F.SilkS")
		)
		(fp_rect
			(start -0.8001 1.6002)
			(end 0.8001 -1.6002)
			(stroke
				(width 0)
				(type default)
			)
			(fill no)
			(layer "F.CrtYd")
		)
		(fp_poly
			(pts
				(xy -1.5621 2.4511) (xy -1.5621 1.6002) (xy 0.8001 1.6002) (xy 0.8001 -1.6002) (xy -0.8001 -1.6002)
				(xy -0.8001 1.5875) (xy -1.5621 1.5875) (xy -1.5621 -2.4511) (xy 1.5621 -2.4511) (xy 1.5621 2.4511)
			)
			(stroke
				(width 0)
				(type default)
			)
			(fill no)
			(layer "F.CrtYd")
		)
		(fp_rect
			(start -1.5621 2.4511)
			(end 1.5621 -2.4511)
			(stroke
				(width 0)
				(type default)
			)
			(fill no)
			(layer "F.Fab")
		)
		(pad "1" smd rect
			(at 0 -1.392936 270)
			(size 2.1082 1.4478)
			(layers "F.Cu" "F.Mask" "F.Paste")
			(net "P0V9_VIN")
		)
		(pad "2" smd rect
			(at 0 1.392936 270)
			(size 2.1082 1.4478)
			(layers "F.Cu" "F.Mask" "F.Paste")
			(net "GND")
		)
	)
	(footprint ""
		(layer "F.Cu")
		(at 20.642326 -130.32486 90)
		(property "Reference" "R348"
			(at 0 0 90)
			(layer "F.SilkS")
			(hide yes)
			(effects
				(font
					(size 1.27 1.27)
				)
			)
		)
		(property "Value" "3K3R2F-2-GP"
			(at 0.064008 -3.993896 90)
			(unlocked yes)
			(layer "F.Fab")
			(hide yes)
			(effects
				(font
					(size 1.016 1.016)
					(thickness 0.1524)
				)
			)
		)
		(property "Device Type" "R402H16"
			(at 0.064008 -5.517896 90)
			(unlocked yes)
			(layer "F.Fab")
			(hide yes)
			(effects
				(font
					(size 1.016 1.016)
					(thickness 0.1524)
				)
			)
		)
		(duplicate_pad_numbers_are_jumpers no)
		(fp_line
			(start 0.508 -0.9398)
			(end -0.508 -0.9398)
			(stroke
				(width 0.1524)
				(type default)
			)
			(layer "F.SilkS")
		)
		(fp_line
			(start -0.508 -0.9398)
			(end -0.508 0.9398)
			(stroke
				(width 0.1524)
				(type default)
			)
			(layer "F.SilkS")
		)
		(fp_rect
			(start -0.508 0.9398)
			(end 0.508 -0.9398)
			(stroke
				(width 0)
				(type default)
			)
			(fill no)
			(layer "F.CrtYd")
		)
		(fp_rect
			(start -0.508 0.9398)
			(end 0.508 -0.9398)
			(stroke
				(width 0)
				(type default)
			)
			(fill no)
			(layer "F.Fab")
		)
		(pad "1" smd custom
			(at 0 -0.4445 90)
			(size 0.1397 0.1397)
			(layers "F.Cu" "F.Mask" "F.Paste")
			(net "P3V3_STBY")
			(options
				(clearance outline)
				(anchor circle)
			)
			(primitives
				(gr_poly
					(pts
						(arc
							(start -0.1778 -0.2794)
							(mid -0.249642 -0.249642)
							(end -0.2794 -0.1778)
						)
						(arc
							(start -0.2794 0.1778)
							(mid -0.249642 0.249642)
							(end -0.1778 0.2794)
						)
						(arc
							(start 0.1778 0.2794)
							(mid 0.249642 0.249642)
							(end 0.2794 0.1778)
						)
						(arc
							(start 0.2794 -0.1778)
							(mid 0.249642 -0.249642)
							(end 0.1778 -0.2794)
						)
					)
					(width 0)
					(fill yes)
				)
			)
		)
		(pad "2" smd custom
			(at 0 0.4445 90)
			(size 0.1397 0.1397)
			(layers "F.Cu" "F.Mask" "F.Paste")
			(net "ROMA10")
			(options
				(clearance outline)
				(anchor circle)
			)
			(primitives
				(gr_poly
					(pts
						(arc
							(start -0.1778 -0.2794)
							(mid -0.249642 -0.249642)
							(end -0.2794 -0.1778)
						)
						(arc
							(start -0.2794 0.1778)
							(mid -0.249642 0.249642)
							(end -0.1778 0.2794)
						)
						(arc
							(start 0.1778 0.2794)
							(mid 0.249642 0.249642)
							(end 0.2794 0.1778)
						)
						(arc
							(start 0.2794 -0.1778)
							(mid 0.249642 -0.249642)
							(end 0.1778 -0.2794)
						)
					)
					(width 0)
					(fill yes)
				)
			)
		)
	)
	(footprint ""
		(layer "F.Cu")
		(at 27.1526 -186.3852)
		(property "Reference" "R502"
			(at 0 0 0)
			(layer "F.SilkS")
			(hide yes)
			(effects
				(font
					(size 1.27 1.27)
				)
			)
		)
		(property "Value" "2KR2F-3-GP"
			(at 0.064008 -3.993896 0)
			(unlocked yes)
			(layer "F.Fab")
			(hide yes)
			(effects
				(font
					(size 1.016 1.016)
					(thickness 0.1524)
				)
			)
		)
		(property "Device Type" "R402H16"
			(at 0.064008 -5.517896 0)
			(unlocked yes)
			(layer "F.Fab")
			(hide yes)
			(effects
				(font
					(size 1.016 1.016)
					(thickness 0.1524)
				)
			)
		)
		(duplicate_pad_numbers_are_jumpers no)
		(fp_line
			(start -0.508 -0.9398)
			(end -0.508 0.9398)
			(stroke
				(width 0.1524)
				(type default)
			)
			(layer "F.SilkS")
		)
		(fp_line
			(start 0.508 -0.9398)
			(end -0.508 -0.9398)
			(stroke
				(width 0.1524)
				(type default)
			)
			(layer "F.SilkS")
		)
		(fp_rect
			(start -0.508 0.9398)
			(end 0.508 -0.9398)
			(stroke
				(width 0)
				(type default)
			)
			(fill no)
			(layer "F.CrtYd")
		)
		(fp_rect
			(start -0.508 0.9398)
			(end 0.508 -0.9398)
			(stroke
				(width 0)
				(type default)
			)
			(fill no)
			(layer "F.Fab")
		)
		(pad "1" smd custom
			(at 0 -0.4445)
			(size 0.1397 0.1397)
			(layers "F.Cu" "F.Mask" "F.Paste")
			(net "P3V3_STBY")
			(options
				(clearance outline)
				(anchor circle)
			)
			(primitives
				(gr_poly
					(pts
						(arc
							(start -0.1778 -0.2794)
							(mid -0.249642 -0.249642)
							(end -0.2794 -0.1778)
						)
						(arc
							(start -0.2794 0.1778)
							(mid -0.249642 0.249642)
							(end -0.1778 0.2794)
						)
						(arc
							(start 0.1778 0.2794)
							(mid 0.249642 0.249642)
							(end 0.2794 0.1778)
						)
						(arc
							(start 0.2794 -0.1778)
							(mid 0.249642 -0.249642)
							(end 0.1778 -0.2794)
						)
					)
					(width 0)
					(fill yes)
				)
			)
		)
		(pad "2" smd custom
			(at 0 0.4445)
			(size 0.1397 0.1397)
			(layers "F.Cu" "F.Mask" "F.Paste")
			(net "BMC_I2C5_SCL_R")
			(options
				(clearance outline)
				(anchor circle)
			)
			(primitives
				(gr_poly
					(pts
						(arc
							(start -0.1778 -0.2794)
							(mid -0.249642 -0.249642)
							(end -0.2794 -0.1778)
						)
						(arc
							(start -0.2794 0.1778)
							(mid -0.249642 0.249642)
							(end -0.1778 0.2794)
						)
						(arc
							(start 0.1778 0.2794)
							(mid 0.249642 0.249642)
							(end 0.2794 0.1778)
						)
						(arc
							(start 0.2794 -0.1778)
							(mid 0.249642 -0.249642)
							(end 0.1778 -0.2794)
						)
					)
					(width 0)
					(fill yes)
				)
			)
		)
	)
	(footprint ""
		(layer "F.Cu")
		(at 340.233 -58.42 -90)
		(property "Reference" "PC218"
			(at 0 0 270)
			(layer "F.SilkS")
			(hide yes)
			(effects
				(font
					(size 1.27 1.27)
				)
			)
		)
		(property "Value" "SC22U25V6KX-GP-U"
			(at -2.860802 -5.279644 270)
			(unlocked yes)
			(layer "F.Fab")
			(hide yes)
			(effects
				(font
					(size 1.016 1.016)
					(thickness 0.1524)
				)
			)
		)
		(property "Device Type" "C1206-TO0D3H75"
			(at -2.860802 -6.803644 270)
			(unlocked yes)
			(layer "F.Fab")
			(hide yes)
			(effects
				(font
					(size 1.016 1.016)
					(thickness 0.1524)
				)
			)
		)
		(duplicate_pad_numbers_are_jumpers no)
		(fp_line
			(start -1.3081 2.3749)
			(end -1.3081 -2.3749)
			(stroke
				(width 0.1524)
				(type default)
			)
			(layer "F.SilkS")
		)
		(fp_line
			(start 1.3081 2.3749)
			(end -1.3081 2.3749)
			(stroke
				(width 0.1524)
				(type default)
			)
			(layer "F.SilkS")
		)
		(fp_line
			(start -1.3081 -2.3749)
			(end 1.3081 -2.3749)
			(stroke
				(width 0.1524)
				(type default)
			)
			(layer "F.SilkS")
		)
		(fp_line
			(start 1.3081 -2.3749)
			(end 1.3081 2.3749)
			(stroke
				(width 0.1524)
				(type default)
			)
			(layer "F.SilkS")
		)
		(fp_rect
			(start -0.8001 1.6002)
			(end 0.8001 -1.6002)
			(stroke
				(width 0)
				(type default)
			)
			(fill no)
			(layer "F.CrtYd")
		)
		(fp_poly
			(pts
				(xy -1.5621 2.4511) (xy -1.5621 1.6002) (xy 0.8001 1.6002) (xy 0.8001 -1.6002) (xy -0.8001 -1.6002)
				(xy -0.8001 1.5875) (xy -1.5621 1.5875) (xy -1.5621 -2.4511) (xy 1.5621 -2.4511) (xy 1.5621 2.4511)
			)
			(stroke
				(width 0)
				(type default)
			)
			(fill no)
			(layer "F.CrtYd")
		)
		(fp_rect
			(start -1.5621 2.4511)
			(end 1.5621 -2.4511)
			(stroke
				(width 0)
				(type default)
			)
			(fill no)
			(layer "F.Fab")
		)
		(pad "1" smd rect
			(at 0 -1.392936 270)
			(size 2.1082 1.4478)
			(layers "F.Cu" "F.Mask" "F.Paste")
			(net "P0V9_E_VIN")
		)
		(pad "2" smd rect
			(at 0 1.392936 270)
			(size 2.1082 1.4478)
			(layers "F.Cu" "F.Mask" "F.Paste")
			(net "GND")
		)
	)
	(footprint ""
		(layer "F.Cu")
		(at 31.9278 -192.1002 90)
		(property "Reference" "R2118"
			(at 0 0 90)
			(layer "F.SilkS")
			(hide yes)
			(effects
				(font
					(size 1.27 1.27)
				)
			)
		)
		(property "Value" "1MR3J-L-GP"
			(at -0.0254 -2.5146 90)
			(unlocked yes)
			(layer "F.Fab")
			(hide yes)
			(effects
				(font
					(size 1.016 1.016)
					(thickness 0.1524)
				)
			)
		)
		(property "Device Type" "R603H22"
			(at -0.0254 -4.0386 90)
			(unlocked yes)
			(layer "F.Fab")
			(hide yes)
			(effects
				(font
					(size 1.016 1.016)
					(thickness 0.1524)
				)
			)
		)
		(duplicate_pad_numbers_are_jumpers no)
		(fp_line
			(start 0.2032 0)
			(end 0.4826 0)
			(stroke
				(width 0.2032)
				(type default)
			)
			(layer "F.SilkS")
		)
		(fp_line
			(start -0.4826 0)
			(end -0.2032 0)
			(stroke
				(width 0.2032)
				(type default)
			)
			(layer "F.SilkS")
		)
		(fp_rect
			(start -0.5842 1.3335)
			(end 0.5842 -1.3335)
			(stroke
				(width 0)
				(type default)
			)
			(fill no)
			(layer "F.CrtYd")
		)
		(fp_rect
			(start -0.5842 1.3335)
			(end 0.5842 -1.3335)
			(stroke
				(width 0)
				(type default)
			)
			(fill no)
			(layer "F.Fab")
		)
		(pad "1" smd custom
			(at 0 -0.762 90)
			(size 0.2159 0.2159)
			(layers "F.Cu" "F.Mask" "F.Paste")
			(net "MB0_CM_GATE_R")
			(options
				(clearance outline)
				(anchor circle)
			)
			(primitives
				(gr_poly
					(pts
						(arc
							(start -0.3302 -0.4318)
							(mid -0.402042 -0.402042)
							(end -0.4318 -0.3302)
						)
						(arc
							(start -0.4318 0.3302)
							(mid -0.402042 0.402042)
							(end -0.3302 0.4318)
						)
						(arc
							(start 0.3302 0.4318)
							(mid 0.402042 0.402042)
							(end 0.4318 0.3302)
						)
						(arc
							(start 0.4318 -0.3302)
							(mid 0.402042 -0.402042)
							(end 0.3302 -0.4318)
						)
					)
					(width 0)
					(fill yes)
				)
			)
		)
		(pad "2" smd custom
			(at 0 0.762 90)
			(size 0.2159 0.2159)
			(layers "F.Cu" "F.Mask" "F.Paste")
			(net "GND")
			(options
				(clearance outline)
				(anchor circle)
			)
			(primitives
				(gr_poly
					(pts
						(arc
							(start -0.3302 -0.4318)
							(mid -0.402042 -0.402042)
							(end -0.4318 -0.3302)
						)
						(arc
							(start -0.4318 0.3302)
							(mid -0.402042 0.402042)
							(end -0.3302 0.4318)
						)
						(arc
							(start 0.3302 0.4318)
							(mid 0.402042 0.402042)
							(end 0.4318 0.3302)
						)
						(arc
							(start 0.4318 -0.3302)
							(mid 0.402042 -0.402042)
							(end 0.3302 -0.4318)
						)
					)
					(width 0)
					(fill yes)
				)
			)
		)
	)
	(footprint ""
		(layer "F.Cu")
		(at 76.689966 -90.61196 180)
		(property "Reference" "SR707"
			(at 0 0 180)
			(layer "F.SilkS")
			(hide yes)
			(effects
				(font
					(size 1.27 1.27)
				)
			)
		)
		(property "Value" "150R2F-1-GP"
			(at 0.064008 -3.993896 180)
			(unlocked yes)
			(layer "F.Fab")
			(hide yes)
			(effects
				(font
					(size 1.016 1.016)
					(thickness 0.1524)
				)
			)
		)
		(property "Device Type" "R402H16"
			(at 0.064008 -5.517896 180)
			(unlocked yes)
			(layer "F.Fab")
			(hide yes)
			(effects
				(font
					(size 1.016 1.016)
					(thickness 0.1524)
				)
			)
		)
		(duplicate_pad_numbers_are_jumpers no)
		(fp_line
			(start 0.508 -0.9398)
			(end -0.508 -0.9398)
			(stroke
				(width 0.1524)
				(type default)
			)
			(layer "F.SilkS")
		)
		(fp_line
			(start -0.508 -0.9398)
			(end -0.508 0.9398)
			(stroke
				(width 0.1524)
				(type default)
			)
			(layer "F.SilkS")
		)
		(fp_rect
			(start -0.508 0.9398)
			(end 0.508 -0.9398)
			(stroke
				(width 0)
				(type default)
			)
			(fill no)
			(layer "F.CrtYd")
		)
		(fp_rect
			(start -0.508 0.9398)
			(end 0.508 -0.9398)
			(stroke
				(width 0)
				(type default)
			)
			(fill no)
			(layer "F.Fab")
		)
		(pad "1" smd custom
			(at 0 -0.4445 180)
			(size 0.1397 0.1397)
			(layers "F.Cu" "F.Mask" "F.Paste")
			(net "P3V3_STBY")
			(options
				(clearance outline)
				(anchor circle)
			)
			(primitives
				(gr_poly
					(pts
						(arc
							(start -0.1778 -0.2794)
							(mid -0.249642 -0.249642)
							(end -0.2794 -0.1778)
						)
						(arc
							(start -0.2794 0.1778)
							(mid -0.249642 0.249642)
							(end -0.1778 0.2794)
						)
						(arc
							(start 0.1778 0.2794)
							(mid 0.249642 0.249642)
							(end 0.2794 0.1778)
						)
						(arc
							(start 0.2794 -0.1778)
							(mid 0.249642 -0.249642)
							(end 0.1778 -0.2794)
						)
					)
					(width 0)
					(fill yes)
				)
			)
		)
		(pad "2" smd custom
			(at 0 0.4445 180)
			(size 0.1397 0.1397)
			(layers "F.Cu" "F.Mask" "F.Paste")
			(net "EXP_BMC_HB_LED_R")
			(options
				(clearance outline)
				(anchor circle)
			)
			(primitives
				(gr_poly
					(pts
						(arc
							(start -0.1778 -0.2794)
							(mid -0.249642 -0.249642)
							(end -0.2794 -0.1778)
						)
						(arc
							(start -0.2794 0.1778)
							(mid -0.249642 0.249642)
							(end -0.1778 0.2794)
						)
						(arc
							(start 0.1778 0.2794)
							(mid 0.249642 0.249642)
							(end 0.2794 0.1778)
						)
						(arc
							(start 0.2794 -0.1778)
							(mid 0.249642 -0.249642)
							(end 0.1778 -0.2794)
						)
					)
					(width 0)
					(fill yes)
				)
			)
		)
	)
)
